# S9S_MB_2U (Grand Teton) — schematic netlist excerpt (pin names and nets, part order shuffled) for the footprints in the layout excerpt that follows; sources: Cadence DE-HDL packaged netlist, KiCad conversion of 03242023_DA0F0TMBIJ0_F0T_Motherboard_J_brd_V01_OCP.brd

C343  Q_CAP  47UF 4V 20% X6S  pkg C0805  page 79 : A = PVCCIN_CPU1 ; B = GND
R3023  Q_RES  0 5% CHIP  pkg 0402LF  page 117 : A = H_CPU_PM_FAST_WAKE_N ; B = H_CPU1_PM_FAST_WAKE_N
PR146  Q_RES  2.2 1% CHIP  pkg 0402LF  page 268 : A = PVCCIN_CPU0_PVCC ; B = PVCCIN_CPU0_VDD4

(kicad_pcb
	(version 20260206)
	(generator "pcbnew")
	(generator_version "10.0")
	(general
		(thickness 1.6)
		(legacy_teardrops no)
	)
	(paper "A4")
	(title_block
		(title "03242023_DA0F0TMBIJ0_F0T_Motherboard_J_brd_V01_OCP.brd")
		(comment 1 "Grand Teton / footprints 4897-4899 of 6105")
	)
	(layers
		(0 "F.Cu" signal "TOP")
		(4 "In1.Cu" signal "GND")
		(6 "In2.Cu" signal "IN1")
		(8 "In3.Cu" signal "GND1")
		(10 "In4.Cu" signal "IN2")
		(12 "In5.Cu" signal "GND2")
		(14 "In6.Cu" signal "IN3")
		(16 "In7.Cu" signal "GND3")
		(18 "In8.Cu" signal "VCC")
		(20 "In9.Cu" signal "VCC1")
		(22 "In10.Cu" signal "GND4")
		(24 "In11.Cu" signal "IN4")
		(26 "In12.Cu" signal "GND5")
		(28 "In13.Cu" signal "IN5")
		(30 "In14.Cu" signal "GND6")
		(32 "In15.Cu" signal "IN6")
		(34 "In16.Cu" signal "GND7")
		(2 "B.Cu" signal "BOTTOM")
		(9 "F.Adhes" user "F.Adhesive")
		(11 "B.Adhes" user "B.Adhesive")
		(13 "F.Paste" user "Package Geometry/Pastemask Top")
		(15 "B.Paste" user "Package Geometry/Pastemask Bottom")
		(5 "F.SilkS" user "Ref Des/Silkscreen Top")
		(7 "B.SilkS" user "Ref Des/Silkscreen Bottom")
		(1 "F.Mask" user "Board Geometry/Soldermask Top")
		(3 "B.Mask" user "Board Geometry/Soldermask Bottom")
		(17 "Dwgs.User" user "User.Drawings")
		(19 "Cmts.User" user "User.Comments")
		(21 "Eco1.User" user "User.Eco1")
		(23 "Eco2.User" user "User.Eco2")
		(25 "Edge.Cuts" user "Board Geometry/Outline")
		(27 "Margin" user)
		(31 "F.CrtYd" user "Package Geometry/Place Bound Top")
		(29 "B.CrtYd" user "Package Geometry/Place Bound Bottom")
		(35 "F.Fab" user "Ref Des/Assembly Top")
		(33 "B.Fab" user "Ref Des/Assembly Bottom")
	)
	(footprint ""
		(layer "B.Cu")
		(at 115.195604 -294.01008 180)
		(property "Reference" "C343"
			(at 0 0 0)
			(layer "B.SilkS")
			(hide yes)
			(effects
				(font
					(size 1.27 1.27)
				)
				(justify mirror)
			)
		)
		(property "Value" ""
			(at 0 0 0)
			(layer "B.Fab")
			(effects
				(font
					(size 1.27 1.27)
				)
				(justify mirror)
			)
		)
		(duplicate_pad_numbers_are_jumpers no)
		(fp_line
			(start 1.524 0.762)
			(end 1.524 -0.762)
			(stroke
				(width 0.1524)
				(type default)
			)
			(layer "B.SilkS")
		)
		(fp_line
			(start 1.524 -0.762)
			(end -1.524 -0.762)
			(stroke
				(width 0.1524)
				(type default)
			)
			(layer "B.SilkS")
		)
		(fp_line
			(start -1.524 0.762)
			(end 1.524 0.762)
			(stroke
				(width 0.1524)
				(type default)
			)
			(layer "B.SilkS")
		)
		(fp_line
			(start -1.524 -0.762)
			(end -1.524 0.762)
			(stroke
				(width 0.1524)
				(type default)
			)
			(layer "B.SilkS")
		)
		(fp_line
			(start 1.1049 0.724916)
			(end -1.1049 0.724916)
			(stroke
				(width 0.1)
				(type default)
			)
			(layer "B.Fab")
		)
		(fp_line
			(start 1.1049 -0.724916)
			(end 1.1049 0.724916)
			(stroke
				(width 0.1)
				(type default)
			)
			(layer "B.Fab")
		)
		(fp_line
			(start -1.1049 0.724916)
			(end -1.1049 -0.724916)
			(stroke
				(width 0.1)
				(type default)
			)
			(layer "B.Fab")
		)
		(fp_line
			(start -1.1049 -0.724916)
			(end 1.1049 -0.724916)
			(stroke
				(width 0.1)
				(type default)
			)
			(layer "B.Fab")
		)
		(pad "1" smd rect
			(at 0.889 0 180)
			(size 1.016 1.27)
			(layers "B.Cu" "B.Mask" "B.Paste")
			(net "PVCCIN_CPU1")
		)
		(pad "2" smd rect
			(at -0.889 0 180)
			(size 1.016 1.27)
			(layers "B.Cu" "B.Mask" "B.Paste")
			(net "GND")
		)
	)
	(footprint ""
		(layer "B.Cu")
		(at 367.012474 -334.693514 -90)
		(property "Reference" "PR146"
			(at 0 0 90)
			(layer "B.SilkS")
			(hide yes)
			(effects
				(font
					(size 1.27 1.27)
				)
				(justify mirror)
			)
		)
		(property "Value" ""
			(at 0 0 90)
			(layer "B.Fab")
			(effects
				(font
					(size 1.27 1.27)
				)
				(justify mirror)
			)
		)
		(duplicate_pad_numbers_are_jumpers no)
		(fp_line
			(start -0.7874 0.4064)
			(end 0.7874 0.4064)
			(stroke
				(width 0.1524)
				(type default)
			)
			(layer "B.SilkS")
		)
		(fp_line
			(start 0.7874 0.4064)
			(end 0.7874 -0.4064)
			(stroke
				(width 0.1524)
				(type default)
			)
			(layer "B.SilkS")
		)
		(fp_line
			(start -0.7874 -0.4064)
			(end -0.7874 0.4064)
			(stroke
				(width 0.1524)
				(type default)
			)
			(layer "B.SilkS")
		)
		(fp_line
			(start 0.7874 -0.4064)
			(end -0.7874 -0.4064)
			(stroke
				(width 0.1524)
				(type default)
			)
			(layer "B.SilkS")
		)
		(fp_line
			(start -0.67945 0.3048)
			(end -0.120396 0.3048)
			(stroke
				(width 0.1)
				(type default)
			)
			(layer "B.Fab")
		)
		(fp_line
			(start -0.120396 0.3048)
			(end -0.120396 0.2794)
			(stroke
				(width 0.1)
				(type default)
			)
			(layer "B.Fab")
		)
		(fp_line
			(start 0.12065 0.3048)
			(end 0.67945 0.3048)
			(stroke
				(width 0.1)
				(type default)
			)
			(layer "B.Fab")
		)
		(fp_line
			(start 0.67945 0.3048)
			(end 0.67945 -0.305054)
			(stroke
				(width 0.1)
				(type default)
			)
			(layer "B.Fab")
		)
		(fp_line
			(start -0.120396 0.2794)
			(end 0.12065 0.2794)
			(stroke
				(width 0.1)
				(type default)
			)
			(layer "B.Fab")
		)
		(fp_line
			(start 0.12065 0.2794)
			(end 0.12065 0.3048)
			(stroke
				(width 0.1)
				(type default)
			)
			(layer "B.Fab")
		)
		(fp_line
			(start -0.12065 -0.2794)
			(end -0.12065 -0.3048)
			(stroke
				(width 0.1)
				(type default)
			)
			(layer "B.Fab")
		)
		(fp_line
			(start 0.12065 -0.2794)
			(end -0.12065 -0.2794)
			(stroke
				(width 0.1)
				(type default)
			)
			(layer "B.Fab")
		)
		(fp_line
			(start -0.67945 -0.3048)
			(end -0.67945 0.3048)
			(stroke
				(width 0.1)
				(type default)
			)
			(layer "B.Fab")
		)
		(fp_line
			(start -0.12065 -0.3048)
			(end -0.67945 -0.3048)
			(stroke
				(width 0.1)
				(type default)
			)
			(layer "B.Fab")
		)
		(fp_line
			(start 0.12065 -0.305054)
			(end 0.12065 -0.2794)
			(stroke
				(width 0.1)
				(type default)
			)
			(layer "B.Fab")
		)
		(fp_line
			(start 0.67945 -0.305054)
			(end 0.12065 -0.305054)
			(stroke
				(width 0.1)
				(type default)
			)
			(layer "B.Fab")
		)
		(pad "1" smd circle
			(at 0.40005 0 90)
			(size 0 0)
			(layers "B.Cu" "B.Mask" "B.Paste")
			(net "PVCCIN_CPU0_PVCC")
		)
		(pad "2" smd circle
			(at -0.40005 0 90)
			(size 0 0)
			(layers "B.Cu" "B.Mask" "B.Paste")
			(net "PVCCIN_CPU0_VDD4")
		)
	)
	(footprint ""
		(layer "B.Cu")
		(at 154.48915 -192.79362 -90)
		(property "Reference" "R3023"
			(at 0 0 90)
			(layer "B.SilkS")
			(hide yes)
			(effects
				(font
					(size 1.27 1.27)
				)
				(justify mirror)
			)
		)
		(property "Value" ""
			(at 0 0 90)
			(layer "B.Fab")
			(effects
				(font
					(size 1.27 1.27)
				)
				(justify mirror)
			)
		)
		(duplicate_pad_numbers_are_jumpers no)
		(fp_line
			(start -0.7874 0.4064)
			(end 0.7874 0.4064)
			(stroke
				(width 0.1524)
				(type default)
			)
			(layer "B.SilkS")
		)
		(fp_line
			(start 0.7874 0.4064)
			(end 0.7874 -0.4064)
			(stroke
				(width 0.1524)
				(type default)
			)
			(layer "B.SilkS")
		)
		(fp_line
			(start -0.7874 -0.4064)
			(end -0.7874 0.4064)
			(stroke
				(width 0.1524)
				(type default)
			)
			(layer "B.SilkS")
		)
		(fp_line
			(start 0.7874 -0.4064)
			(end -0.7874 -0.4064)
			(stroke
				(width 0.1524)
				(type default)
			)
			(layer "B.SilkS")
		)
		(fp_line
			(start -0.67945 0.3048)
			(end -0.120396 0.3048)
			(stroke
				(width 0.1)
				(type default)
			)
			(layer "B.Fab")
		)
		(fp_line
			(start -0.120396 0.3048)
			(end -0.120396 0.2794)
			(stroke
				(width 0.1)
				(type default)
			)
			(layer "B.Fab")
		)
		(fp_line
			(start 0.12065 0.3048)
			(end 0.67945 0.3048)
			(stroke
				(width 0.1)
				(type default)
			)
			(layer "B.Fab")
		)
		(fp_line
			(start 0.67945 0.3048)
			(end 0.67945 -0.305054)
			(stroke
				(width 0.1)
				(type default)
			)
			(layer "B.Fab")
		)
		(fp_line
			(start -0.120396 0.2794)
			(end 0.12065 0.2794)
			(stroke
				(width 0.1)
				(type default)
			)
			(layer "B.Fab")
		)
		(fp_line
			(start 0.12065 0.2794)
			(end 0.12065 0.3048)
			(stroke
				(width 0.1)
				(type default)
			)
			(layer "B.Fab")
		)
		(fp_line
			(start -0.12065 -0.2794)
			(end -0.12065 -0.3048)
			(stroke
				(width 0.1)
				(type default)
			)
			(layer "B.Fab")
		)
		(fp_line
			(start 0.12065 -0.2794)
			(end -0.12065 -0.2794)
			(stroke
				(width 0.1)
				(type default)
			)
			(layer "B.Fab")
		)
		(fp_line
			(start -0.67945 -0.3048)
			(end -0.67945 0.3048)
			(stroke
				(width 0.1)
				(type default)
			)
			(layer "B.Fab")
		)
		(fp_line
			(start -0.12065 -0.3048)
			(end -0.67945 -0.3048)
			(stroke
				(width 0.1)
				(type default)
			)
			(layer "B.Fab")
		)
		(fp_line
			(start 0.12065 -0.305054)
			(end 0.12065 -0.2794)
			(stroke
				(width 0.1)
				(type default)
			)
			(layer "B.Fab")
		)
		(fp_line
			(start 0.67945 -0.305054)
			(end 0.12065 -0.305054)
			(stroke
				(width 0.1)
				(type default)
			)
			(layer "B.Fab")
		)
		(pad "1" smd circle
			(at 0.40005 0 90)
			(size 0 0)
			(layers "B.Cu" "B.Mask" "B.Paste")
			(net "H_CPU_PM_FAST_WAKE_N")
		)
		(pad "2" smd circle
			(at -0.40005 0 90)
			(size 0 0)
			(layers "B.Cu" "B.Mask" "B.Paste")
			(net "H_CPU1_PM_FAST_WAKE_N")
		)
	)
)
